(kicad_pcb
	(version 20260206)
	(generator "pcbnew")
	(generator_version "10.0")
	(general
		(thickness 1.6)
		(legacy_teardrops no)
	)
	(paper "A4")
	(title_block
		(title "Bryce Canyon_SCC_16316-1_OCP.brd")
		(comment 1 "Bryce Canyon / footprint 482 of 1561 (U2), pads 727-849 of 896")
	)
	(layers
		(0 "F.Cu" signal "TOP")
		(4 "In1.Cu" signal "L2GND")
		(6 "In2.Cu" signal "L3")
		(8 "In3.Cu" signal "L4VCC")
		(10 "In4.Cu" signal "L5VCC")
		(12 "In5.Cu" signal "L6")
		(14 "In6.Cu" signal "L7GND")
		(2 "B.Cu" signal "BOTTOM")
		(9 "F.Adhes" user "F.Adhesive")
		(11 "B.Adhes" user "B.Adhesive")
		(13 "F.Paste" user "Package Geometry/Pastemask Top")
		(15 "B.Paste" user "Package Geometry/Pastemask Bottom")
		(5 "F.SilkS" user "Ref Des/Silkscreen Top")
		(7 "B.SilkS" user "Ref Des/Silkscreen Bottom")
		(1 "F.Mask" user "Board Geometry/Soldermask Top")
		(3 "B.Mask" user "Board Geometry/Soldermask Bottom")
		(17 "Dwgs.User" user "User.Drawings")
		(19 "Cmts.User" user "User.Comments")
		(21 "Eco1.User" user "User.Eco1")
		(23 "Eco2.User" user "User.Eco2")
		(25 "Edge.Cuts" user "Board Geometry/Outline")
		(27 "Margin" user)
		(31 "F.CrtYd" user "Package Geometry/Place Bound Top")
		(29 "B.CrtYd" user "Package Geometry/Place Bound Bottom")
		(35 "F.Fab" user "Ref Des/Assembly Top")
		(33 "B.Fab" user "Ref Des/Assembly Bottom")
	)
	(footprint ""
		(layer "F.Cu")
		(at 174.999904 -39.99992)
		(property "Reference" "U2"
			(at 0 0 0)
			(layer "F.SilkS")
			(hide yes)
			(effects
				(font
					(size 1.27 1.27)
				)
			)
		)
		(property "Value" "SAS3008C0-1-DB-500020657-1-GP"
			(at -20.374102 -5.0292 0)
			(unlocked yes)
			(layer "F.Fab")
			(hide yes)
			(effects
				(font
					(size 1.016 1.016)
					(thickness 0.1524)
				)
			)
		)
		(property "Device Type" "BGA896D25H78"
			(at -20.374102 -6.5532 0)
			(unlocked yes)
			(layer "F.Fab")
			(hide yes)
			(effects
				(font
					(size 1.016 1.016)
					(thickness 0.1524)
				)
			)
		)
		(duplicate_pad_numbers_are_jumpers no)
		(pad "R11" smd circle
			(at -3.599942 -0.40005)
			(size 0.3556 0.3556)
			(layers "F.Cu" "F.Mask" "F.Paste")
			(net "GND")
		)
		(pad "R12" smd circle
			(at -2.800096 -0.40005)
			(size 0.3556 0.3556)
			(layers "F.Cu" "F.Mask" "F.Paste")
			(net "P0V975")
		)
		(pad "R13" smd circle
			(at -1.999996 -0.40005)
			(size 0.3556 0.3556)
			(layers "F.Cu" "F.Mask" "F.Paste")
			(net "GND")
		)
		(pad "R14" smd circle
			(at -1.199896 -0.40005)
			(size 0.3556 0.3556)
			(layers "F.Cu" "F.Mask" "F.Paste")
			(net "P0V975")
		)
		(pad "R15" smd circle
			(at -0.40005 -0.40005)
			(size 0.3556 0.3556)
			(layers "F.Cu" "F.Mask" "F.Paste")
			(net "GND")
		)
		(pad "R16" smd circle
			(at 0.40005 -0.40005)
			(size 0.3556 0.3556)
			(layers "F.Cu" "F.Mask" "F.Paste")
			(net "P0V975")
		)
		(pad "R17" smd circle
			(at 1.199896 -0.40005)
			(size 0.3556 0.3556)
			(layers "F.Cu" "F.Mask" "F.Paste")
			(net "GND")
		)
		(pad "R18" smd circle
			(at 1.999996 -0.40005)
			(size 0.3556 0.3556)
			(layers "F.Cu" "F.Mask" "F.Paste")
			(net "P0V975")
		)
		(pad "R19" smd circle
			(at 2.800096 -0.40005)
			(size 0.3556 0.3556)
			(layers "F.Cu" "F.Mask" "F.Paste")
			(net "GND")
		)
		(pad "R20" smd circle
			(at 3.599942 -0.40005)
			(size 0.3556 0.3556)
			(layers "F.Cu" "F.Mask" "F.Paste")
			(net "P0V975")
		)
		(pad "R21" smd circle
			(at 4.400042 -0.40005)
			(size 0.3556 0.3556)
			(layers "F.Cu" "F.Mask" "F.Paste")
			(net "GND")
		)
		(pad "R22" smd circle
			(at 5.199888 -0.40005)
			(size 0.3556 0.3556)
			(layers "F.Cu" "F.Mask" "F.Paste")
			(net "GND")
		)
		(pad "R23" smd circle
			(at 5.999988 -0.40005)
			(size 0.3556 0.3556)
			(layers "F.Cu" "F.Mask" "F.Paste")
			(net "GND")
		)
		(pad "R24" smd circle
			(at 6.800088 -0.40005)
			(size 0.3556 0.3556)
			(layers "F.Cu" "F.Mask" "F.Paste")
			(net "GND")
		)
		(pad "R25" smd circle
			(at 7.599934 -0.40005)
			(size 0.3556 0.3556)
			(layers "F.Cu" "F.Mask" "F.Paste")
			(net "GND")
		)
		(pad "R26" smd circle
			(at 8.400034 -0.40005)
			(size 0.3556 0.3556)
			(layers "F.Cu" "F.Mask" "F.Paste")
			(net "GND")
		)
		(pad "R27" smd circle
			(at 9.19988 -0.40005)
			(size 0.3556 0.3556)
			(layers "F.Cu" "F.Mask" "F.Paste")
			(net "P1V8_C")
		)
		(pad "R28" smd circle
			(at 9.99998 -0.40005)
			(size 0.3556 0.3556)
			(layers "F.Cu" "F.Mask" "F.Paste")
			(net "I2C_IOC_4_SDA")
		)
		(pad "R29" smd circle
			(at 10.80008 -0.40005)
			(size 0.3556 0.3556)
			(layers "F.Cu" "F.Mask" "F.Paste")
			(net "I2C_IOC_0_SDA")
		)
		(pad "R30" smd circle
			(at 11.599926 -0.40005)
			(size 0.3556 0.3556)
			(layers "F.Cu" "F.Mask" "F.Paste")
			(net "SYS_CORE_TRI#")
		)
		(pad "T1" smd circle
			(at -11.599926 0.40005)
			(size 0.3556 0.3556)
			(layers "F.Cu" "F.Mask" "F.Paste")
			(net "RTRIM")
		)
		(pad "T2" smd circle
			(at -10.80008 0.40005)
			(size 0.3556 0.3556)
			(layers "F.Cu" "F.Mask" "F.Paste")
			(net "RTRIM#")
		)
		(pad "T3" smd circle
			(at -9.99998 0.40005)
			(size 0.3556 0.3556)
			(layers "F.Cu" "F.Mask" "F.Paste")
			(net "GND")
		)
		(pad "T4" smd circle
			(at -9.19988 0.40005)
			(size 0.3556 0.3556)
			(layers "F.Cu" "F.Mask" "F.Paste")
			(net "OSC_REF_CLK")
		)
		(pad "T5" smd circle
			(at -8.400034 0.40005)
			(size 0.3556 0.3556)
			(layers "F.Cu" "F.Mask" "F.Paste")
			(net "GND")
		)
		(pad "T6" smd circle
			(at -7.599934 0.40005)
			(size 0.3556 0.3556)
			(layers "F.Cu" "F.Mask" "F.Paste")
			(net "SIO_DIN_0")
		)
		(pad "T7" smd circle
			(at -6.800088 0.40005)
			(size 0.3556 0.3556)
			(layers "F.Cu" "F.Mask" "F.Paste")
			(net "GND")
		)
		(pad "T8" smd circle
			(at -5.999988 0.40005)
			(size 0.3556 0.3556)
			(layers "F.Cu" "F.Mask" "F.Paste")
			(net "GND")
		)
		(pad "T9" smd circle
			(at -5.199888 0.40005)
			(size 0.3556 0.3556)
			(layers "F.Cu" "F.Mask" "F.Paste")
			(net "SYS_PLL_VDD")
		)
		(pad "T10" smd circle
			(at -4.400042 0.40005)
			(size 0.3556 0.3556)
			(layers "F.Cu" "F.Mask" "F.Paste")
			(net "GND")
		)
		(pad "T11" smd circle
			(at -3.599942 0.40005)
			(size 0.3556 0.3556)
			(layers "F.Cu" "F.Mask" "F.Paste")
			(net "GND")
		)
		(pad "T12" smd circle
			(at -2.800096 0.40005)
			(size 0.3556 0.3556)
			(layers "F.Cu" "F.Mask" "F.Paste")
			(net "GND")
		)
		(pad "T13" smd circle
			(at -1.999996 0.40005)
			(size 0.3556 0.3556)
			(layers "F.Cu" "F.Mask" "F.Paste")
			(net "P0V975")
		)
		(pad "T14" smd circle
			(at -1.199896 0.40005)
			(size 0.3556 0.3556)
			(layers "F.Cu" "F.Mask" "F.Paste")
			(net "GND")
		)
		(pad "T15" smd circle
			(at -0.40005 0.40005)
			(size 0.3556 0.3556)
			(layers "F.Cu" "F.Mask" "F.Paste")
			(net "P0V975")
		)
		(pad "T16" smd circle
			(at 0.40005 0.40005)
			(size 0.3556 0.3556)
			(layers "F.Cu" "F.Mask" "F.Paste")
			(net "GND")
		)
		(pad "T17" smd circle
			(at 1.199896 0.40005)
			(size 0.3556 0.3556)
			(layers "F.Cu" "F.Mask" "F.Paste")
			(net "P0V975")
		)
		(pad "T18" smd circle
			(at 1.999996 0.40005)
			(size 0.3556 0.3556)
			(layers "F.Cu" "F.Mask" "F.Paste")
			(net "GND")
		)
		(pad "T19" smd circle
			(at 2.800096 0.40005)
			(size 0.3556 0.3556)
			(layers "F.Cu" "F.Mask" "F.Paste")
			(net "P0V975")
		)
		(pad "T20" smd circle
			(at 3.599942 0.40005)
			(size 0.3556 0.3556)
			(layers "F.Cu" "F.Mask" "F.Paste")
			(net "GND")
		)
		(pad "T21" smd circle
			(at 4.400042 0.40005)
			(size 0.3556 0.3556)
			(layers "F.Cu" "F.Mask" "F.Paste")
			(net "P0V975")
		)
		(pad "T22" smd circle
			(at 5.199888 0.40005)
			(size 0.3556 0.3556)
			(layers "F.Cu" "F.Mask" "F.Paste")
			(net "GND")
		)
		(pad "T23" smd circle
			(at 5.999988 0.40005)
			(size 0.3556 0.3556)
			(layers "F.Cu" "F.Mask" "F.Paste")
			(net "GND")
		)
		(pad "T24" smd circle
			(at 6.800088 0.40005)
			(size 0.3556 0.3556)
			(layers "F.Cu" "F.Mask" "F.Paste")
			(net "GND")
		)
		(pad "T25" smd circle
			(at 7.599934 0.40005)
			(size 0.3556 0.3556)
			(layers "F.Cu" "F.Mask" "F.Paste")
			(net "GND")
		)
		(pad "T26" smd circle
			(at 8.400034 0.40005)
			(size 0.3556 0.3556)
			(layers "F.Cu" "F.Mask" "F.Paste")
			(net "P1V8_C")
		)
		(pad "T27" smd circle
			(at 9.19988 0.40005)
			(size 0.3556 0.3556)
			(layers "F.Cu" "F.Mask" "F.Paste")
			(net "GND")
		)
		(pad "T28" smd circle
			(at 9.99998 0.40005)
			(size 0.3556 0.3556)
			(layers "F.Cu" "F.Mask" "F.Paste")
			(net "IOC_CLK_SEL1")
		)
		(pad "T29" smd circle
			(at 10.80008 0.40005)
			(size 0.3556 0.3556)
			(layers "F.Cu" "F.Mask" "F.Paste")
			(net "SYS_HB_LED")
		)
		(pad "T30" smd circle
			(at 11.599926 0.40005)
			(size 0.3556 0.3556)
			(layers "F.Cu" "F.Mask" "F.Paste")
			(net "SBL_SCL")
		)
		(pad "U1" smd circle
			(at -11.599926 1.199896)
			(size 0.3556 0.3556)
			(layers "F.Cu" "F.Mask" "F.Paste")
			(net "SAS0_VDDH")
		)
		(pad "U2" smd circle
			(at -10.80008 1.199896)
			(size 0.3556 0.3556)
			(layers "F.Cu" "F.Mask" "F.Paste")
			(net "GND")
		)
		(pad "U3" smd circle
			(at -9.99998 1.199896)
			(size 0.3556 0.3556)
			(layers "F.Cu" "F.Mask" "F.Paste")
			(net "GND")
		)
		(pad "U4" smd circle
			(at -9.19988 1.199896)
			(size 0.3556 0.3556)
			(layers "F.Cu" "F.Mask" "F.Paste")
			(net "GND")
		)
		(pad "U5" smd circle
			(at -8.400034 1.199896)
			(size 0.3556 0.3556)
			(layers "F.Cu" "F.Mask" "F.Paste")
			(net "GND")
		)
		(pad "U6" smd circle
			(at -7.599934 1.199896)
			(size 0.3556 0.3556)
			(layers "F.Cu" "F.Mask" "F.Paste")
			(net "GND")
		)
		(pad "U7" smd circle
			(at -6.800088 1.199896)
			(size 0.3556 0.3556)
			(layers "F.Cu" "F.Mask" "F.Paste")
			(net "GND")
		)
		(pad "U8" smd circle
			(at -5.999988 1.199896)
			(size 0.3556 0.3556)
			(layers "F.Cu" "F.Mask" "F.Paste")
			(net "GND")
		)
		(pad "U9" smd circle
			(at -5.199888 1.199896)
			(size 0.3556 0.3556)
			(layers "F.Cu" "F.Mask" "F.Paste")
			(net "GND")
		)
		(pad "U10" smd circle
			(at -4.400042 1.199896)
			(size 0.3556 0.3556)
			(layers "F.Cu" "F.Mask" "F.Paste")
			(net "SHELL_PLL_VDD")
		)
		(pad "U11" smd circle
			(at -3.599942 1.199896)
			(size 0.3556 0.3556)
			(layers "F.Cu" "F.Mask" "F.Paste")
			(net "GND")
		)
		(pad "U12" smd circle
			(at -2.800096 1.199896)
			(size 0.3556 0.3556)
			(layers "F.Cu" "F.Mask" "F.Paste")
			(net "P0V975")
		)
		(pad "U13" smd circle
			(at -1.999996 1.199896)
			(size 0.3556 0.3556)
			(layers "F.Cu" "F.Mask" "F.Paste")
			(net "GND")
		)
		(pad "U14" smd circle
			(at -1.199896 1.199896)
			(size 0.3556 0.3556)
			(layers "F.Cu" "F.Mask" "F.Paste")
			(net "P0V975")
		)
		(pad "U15" smd circle
			(at -0.40005 1.199896)
			(size 0.3556 0.3556)
			(layers "F.Cu" "F.Mask" "F.Paste")
			(net "GND")
		)
		(pad "U16" smd circle
			(at 0.40005 1.199896)
			(size 0.3556 0.3556)
			(layers "F.Cu" "F.Mask" "F.Paste")
			(net "P0V975")
		)
		(pad "U17" smd circle
			(at 1.199896 1.199896)
			(size 0.3556 0.3556)
			(layers "F.Cu" "F.Mask" "F.Paste")
			(net "GND")
		)
		(pad "U18" smd circle
			(at 1.999996 1.199896)
			(size 0.3556 0.3556)
			(layers "F.Cu" "F.Mask" "F.Paste")
			(net "P0V975")
		)
		(pad "U19" smd circle
			(at 2.800096 1.199896)
			(size 0.3556 0.3556)
			(layers "F.Cu" "F.Mask" "F.Paste")
			(net "GND")
		)
		(pad "U20" smd circle
			(at 3.599942 1.199896)
			(size 0.3556 0.3556)
			(layers "F.Cu" "F.Mask" "F.Paste")
			(net "P0V975")
		)
		(pad "U21" smd circle
			(at 4.400042 1.199896)
			(size 0.3556 0.3556)
			(layers "F.Cu" "F.Mask" "F.Paste")
			(net "GND")
		)
		(pad "U22" smd circle
			(at 5.199888 1.199896)
			(size 0.3556 0.3556)
			(layers "F.Cu" "F.Mask" "F.Paste")
			(net "GND")
		)
		(pad "U23" smd circle
			(at 5.999988 1.199896)
			(size 0.3556 0.3556)
			(layers "F.Cu" "F.Mask" "F.Paste")
			(net "GND")
		)
		(pad "U24" smd circle
			(at 6.800088 1.199896)
			(size 0.3556 0.3556)
			(layers "F.Cu" "F.Mask" "F.Paste")
			(net "GND")
		)
		(pad "U25" smd circle
			(at 7.599934 1.199896)
			(size 0.3556 0.3556)
			(layers "F.Cu" "F.Mask" "F.Paste")
			(net "GND")
		)
		(pad "U26" smd circle
			(at 8.400034 1.199896)
			(size 0.3556 0.3556)
			(layers "F.Cu" "F.Mask" "F.Paste")
			(net "GND")
		)
		(pad "U27" smd circle
			(at 9.19988 1.199896)
			(size 0.3556 0.3556)
			(layers "F.Cu" "F.Mask" "F.Paste")
			(net "P1V8_C")
		)
		(pad "U28" smd circle
			(at 9.99998 1.199896)
			(size 0.3556 0.3556)
			(layers "F.Cu" "F.Mask" "F.Paste")
			(net "IOC_RESET_N")
		)
		(pad "U29" smd circle
			(at 10.80008 1.199896)
			(size 0.3556 0.3556)
			(layers "F.Cu" "F.Mask" "F.Paste")
			(net "I2C_IOC_3_SDA")
		)
		(pad "U30" smd circle
			(at 11.599926 1.199896)
			(size 0.3556 0.3556)
			(layers "F.Cu" "F.Mask" "F.Paste")
			(net "CP_DONE")
		)
		(pad "V1" smd circle
			(at -11.599926 1.999996)
			(size 0.3556 0.3556)
			(layers "F.Cu" "F.Mask" "F.Paste")
			(net "PHY_IOC_TO_SCC_47_DP")
		)
		(pad "V2" smd circle
			(at -10.80008 1.999996)
			(size 0.3556 0.3556)
			(layers "F.Cu" "F.Mask" "F.Paste")
			(net "PHY_IOC_TO_SCC_47_DN")
		)
		(pad "V3" smd circle
			(at -9.99998 1.999996)
			(size 0.3556 0.3556)
			(layers "F.Cu" "F.Mask" "F.Paste")
			(net "GND")
		)
		(pad "V4" smd circle
			(at -9.19988 1.999996)
			(size 0.3556 0.3556)
			(layers "F.Cu" "F.Mask" "F.Paste")
			(net "PHY_SCC_TO_IOC_C_47_DP")
		)
		(pad "V5" smd circle
			(at -8.400034 1.999996)
			(size 0.3556 0.3556)
			(layers "F.Cu" "F.Mask" "F.Paste")
			(net "PHY_SCC_TO_IOC_C_47_DN")
		)
		(pad "V6" smd circle
			(at -7.599934 1.999996)
			(size 0.3556 0.3556)
			(layers "F.Cu" "F.Mask" "F.Paste")
			(net "GND")
		)
		(pad "V7" smd circle
			(at -6.800088 1.999996)
			(size 0.3556 0.3556)
			(layers "F.Cu" "F.Mask" "F.Paste")
			(net "SAS0_AVDD")
		)
		(pad "V8" smd circle
			(at -5.999988 1.999996)
			(size 0.3556 0.3556)
			(layers "F.Cu" "F.Mask" "F.Paste")
			(net "GND")
		)
		(pad "V9" smd circle
			(at -5.199888 1.999996)
			(size 0.3556 0.3556)
			(layers "F.Cu" "F.Mask" "F.Paste")
			(net "SAS0_AVDD")
		)
		(pad "V10" smd circle
			(at -4.400042 1.999996)
			(size 0.3556 0.3556)
			(layers "F.Cu" "F.Mask" "F.Paste")
			(net "GND")
		)
		(pad "V11" smd circle
			(at -3.599942 1.999996)
			(size 0.3556 0.3556)
			(layers "F.Cu" "F.Mask" "F.Paste")
			(net "VDDA_SAS_REF_CLK")
		)
		(pad "V12" smd circle
			(at -2.800096 1.999996)
			(size 0.3556 0.3556)
			(layers "F.Cu" "F.Mask" "F.Paste")
			(net "GND")
		)
		(pad "V13" smd circle
			(at -1.999996 1.999996)
			(size 0.3556 0.3556)
			(layers "F.Cu" "F.Mask" "F.Paste")
			(net "P0V975")
		)
		(pad "V14" smd circle
			(at -1.199896 1.999996)
			(size 0.3556 0.3556)
			(layers "F.Cu" "F.Mask" "F.Paste")
			(net "GND")
		)
		(pad "V15" smd circle
			(at -0.40005 1.999996)
			(size 0.3556 0.3556)
			(layers "F.Cu" "F.Mask" "F.Paste")
			(net "P0V975")
		)
		(pad "V16" smd circle
			(at 0.40005 1.999996)
			(size 0.3556 0.3556)
			(layers "F.Cu" "F.Mask" "F.Paste")
			(net "GND")
		)
		(pad "V17" smd circle
			(at 1.199896 1.999996)
			(size 0.3556 0.3556)
			(layers "F.Cu" "F.Mask" "F.Paste")
			(net "P0V975")
		)
		(pad "V18" smd circle
			(at 1.999996 1.999996)
			(size 0.3556 0.3556)
			(layers "F.Cu" "F.Mask" "F.Paste")
			(net "GND")
		)
		(pad "V19" smd circle
			(at 2.800096 1.999996)
			(size 0.3556 0.3556)
			(layers "F.Cu" "F.Mask" "F.Paste")
			(net "P0V975")
		)
		(pad "V20" smd circle
			(at 3.599942 1.999996)
			(size 0.3556 0.3556)
			(layers "F.Cu" "F.Mask" "F.Paste")
			(net "GND")
		)
		(pad "V21" smd circle
			(at 4.400042 1.999996)
			(size 0.3556 0.3556)
			(layers "F.Cu" "F.Mask" "F.Paste")
			(net "P0V975")
		)
		(pad "V22" smd circle
			(at 5.199888 1.999996)
			(size 0.3556 0.3556)
			(layers "F.Cu" "F.Mask" "F.Paste")
			(net "GND")
		)
		(pad "V23" smd circle
			(at 5.999988 1.999996)
			(size 0.3556 0.3556)
			(layers "F.Cu" "F.Mask" "F.Paste")
			(net "GND")
		)
		(pad "V24" smd circle
			(at 6.800088 1.999996)
			(size 0.3556 0.3556)
			(layers "F.Cu" "F.Mask" "F.Paste")
			(net "GND")
		)
		(pad "V25" smd circle
			(at 7.599934 1.999996)
			(size 0.3556 0.3556)
			(layers "F.Cu" "F.Mask" "F.Paste")
			(net "GND")
		)
		(pad "V26" smd circle
			(at 8.400034 1.999996)
			(size 0.3556 0.3556)
			(layers "F.Cu" "F.Mask" "F.Paste")
			(net "P1V8_C")
		)
		(pad "V27" smd circle
			(at 9.19988 1.999996)
			(size 0.3556 0.3556)
			(layers "F.Cu" "F.Mask" "F.Paste")
			(net "GND")
		)
		(pad "V28" smd circle
			(at 9.99998 1.999996)
			(size 0.3556 0.3556)
			(layers "F.Cu" "F.Mask" "F.Paste")
			(net "I2C_IOC_2_SCL")
		)
		(pad "V29" smd circle
			(at 10.80008 1.999996)
			(size 0.3556 0.3556)
			(layers "F.Cu" "F.Mask" "F.Paste")
			(net "I2C_IOC_0_SCL")
		)
		(pad "V30" smd circle
			(at 11.599926 1.999996)
			(size 0.3556 0.3556)
			(layers "F.Cu" "F.Mask" "F.Paste")
			(net "I2C_IOC_1_SDA")
		)
		(pad "W1" smd circle
			(at -11.599926 2.800096)
			(size 0.3556 0.3556)
			(layers "F.Cu" "F.Mask" "F.Paste")
			(net "PHY_IOC_TO_SCC_46_DP")
		)
		(pad "W2" smd circle
			(at -10.80008 2.800096)
			(size 0.3556 0.3556)
			(layers "F.Cu" "F.Mask" "F.Paste")
			(net "PHY_IOC_TO_SCC_46_DN")
		)
		(pad "W3" smd circle
			(at -9.99998 2.800096)
			(size 0.3556 0.3556)
			(layers "F.Cu" "F.Mask" "F.Paste")
			(net "GND")
		)
		(pad "W4" smd circle
			(at -9.19988 2.800096)
			(size 0.3556 0.3556)
			(layers "F.Cu" "F.Mask" "F.Paste")
			(net "PHY_SCC_TO_IOC_C_46_DP")
		)
		(pad "W5" smd circle
			(at -8.400034 2.800096)
			(size 0.3556 0.3556)
			(layers "F.Cu" "F.Mask" "F.Paste")
			(net "PHY_SCC_TO_IOC_C_46_DN")
		)
		(pad "W6" smd circle
			(at -7.599934 2.800096)
			(size 0.3556 0.3556)
			(layers "F.Cu" "F.Mask" "F.Paste")
			(net "GND")
		)
		(pad "W7" smd circle
			(at -6.800088 2.800096)
			(size 0.3556 0.3556)
			(layers "F.Cu" "F.Mask" "F.Paste")
			(net "GND")
		)
		(pad "W8" smd circle
			(at -5.999988 2.800096)
			(size 0.3556 0.3556)
			(layers "F.Cu" "F.Mask" "F.Paste")
			(net "GND")
		)
		(pad "W9" smd circle
			(at -5.199888 2.800096)
			(size 0.3556 0.3556)
			(layers "F.Cu" "F.Mask" "F.Paste")
			(net "GND")
		)
		(pad "W10" smd circle
			(at -4.400042 2.800096)
			(size 0.3556 0.3556)
			(layers "F.Cu" "F.Mask" "F.Paste")
			(net "GND")
		)
		(pad "W11" smd circle
			(at -3.599942 2.800096)
			(size 0.3556 0.3556)
			(layers "F.Cu" "F.Mask" "F.Paste")
			(net "GND")
		)
		(pad "W12" smd circle
			(at -2.800096 2.800096)
			(size 0.3556 0.3556)
			(layers "F.Cu" "F.Mask" "F.Paste")
			(net "GND")
		)
		(pad "W13" smd circle
			(at -1.999996 2.800096)
			(size 0.3556 0.3556)
			(layers "F.Cu" "F.Mask" "F.Paste")
			(net "GND")
		)
	)
)
